(kicad_pcb
	(version 20260206)
	(generator "pcbnew")
	(generator_version "10.0")
	(general
		(thickness 1.6)
		(legacy_teardrops no)
	)
	(paper "A4")
	(title_block
		(title "01162023_DA0F0TEBIF0_F0T_Expander_BD_F_brd_V02_OCP.brd")
		(comment 1 "Grand Teton / footprints 5168-5172 of 9728")
	)
	(layers
		(0 "F.Cu" signal "TOP")
		(4 "In1.Cu" signal "GND")
		(6 "In2.Cu" signal "VCC")
		(8 "In3.Cu" signal "VCC1")
		(10 "In4.Cu" signal "GND1")
		(12 "In5.Cu" signal "IN1")
		(14 "In6.Cu" signal "GND2")
		(16 "In7.Cu" signal "IN2")
		(18 "In8.Cu" signal "GND3")
		(20 "In9.Cu" signal "IN3")
		(22 "In10.Cu" signal "GND4")
		(24 "In11.Cu" signal "IN4")
		(26 "In12.Cu" signal "GND5")
		(28 "In13.Cu" signal "IN5")
		(30 "In14.Cu" signal "GND6")
		(32 "In15.Cu" signal "IN6")
		(34 "In16.Cu" signal "GND7")
		(2 "B.Cu" signal "BOTTOM")
		(9 "F.Adhes" user "F.Adhesive")
		(11 "B.Adhes" user "B.Adhesive")
		(13 "F.Paste" user "Package Geometry/Pastemask Top")
		(15 "B.Paste" user "Package Geometry/Pastemask Bottom")
		(5 "F.SilkS" user "Ref Des/Silkscreen Top")
		(7 "B.SilkS" user "Ref Des/Silkscreen Bottom")
		(1 "F.Mask" user "Board Geometry/Soldermask Top")
		(3 "B.Mask" user "Board Geometry/Soldermask Bottom")
		(17 "Dwgs.User" user "User.Drawings")
		(19 "Cmts.User" user "User.Comments")
		(21 "Eco1.User" user "User.Eco1")
		(23 "Eco2.User" user "User.Eco2")
		(25 "Edge.Cuts" user "Board Geometry/Outline")
		(27 "Margin" user)
		(31 "F.CrtYd" user "Package Geometry/Place Bound Top")
		(29 "B.CrtYd" user "Package Geometry/Place Bound Bottom")
		(35 "F.Fab" user "Ref Des/Assembly Top")
		(33 "B.Fab" user "Ref Des/Assembly Bottom")
	)
	(footprint ""
		(layer "F.Cu")
		(at 406.005284 -377.889262 90)
		(property "Reference" "U422"
			(at 0.029718 2.129282 0)
			(unlocked yes)
			(layer "F.SilkS")
			(effects
				(font
					(size 0.7874 0.5842)
					(thickness 0.1524)
				)
				(justify left)
			)
		)
		(property "Value" ""
			(at 0 0 90)
			(layer "F.Fab")
			(effects
				(font
					(size 1.27 1.27)
				)
			)
		)
		(duplicate_pad_numbers_are_jumpers no)
		(fp_line
			(start 1.463548 -1.549908)
			(end 1.463548 1.549908)
			(stroke
				(width 0.1524)
				(type default)
			)
			(layer "F.SilkS")
		)
		(fp_line
			(start 0.762 -1.549908)
			(end 1.463548 -1.549908)
			(stroke
				(width 0.1524)
				(type default)
			)
			(layer "F.SilkS")
		)
		(fp_line
			(start -0.787908 -1.549908)
			(end 0 -0.762)
			(stroke
				(width 0.1524)
				(type default)
			)
			(layer "F.SilkS")
		)
		(fp_line
			(start -1.463548 -1.549908)
			(end -0.787908 -1.549908)
			(stroke
				(width 0.1524)
				(type default)
			)
			(layer "F.SilkS")
		)
		(fp_line
			(start 0 -0.762)
			(end 0.762 -1.549908)
			(stroke
				(width 0.1524)
				(type default)
			)
			(layer "F.SilkS")
		)
		(fp_line
			(start 1.463548 1.549908)
			(end -1.463548 1.549908)
			(stroke
				(width 0.1524)
				(type default)
			)
			(layer "F.SilkS")
		)
		(fp_line
			(start -1.463548 1.549908)
			(end -1.463548 -1.549908)
			(stroke
				(width 0.1524)
				(type default)
			)
			(layer "F.SilkS")
		)
		(fp_poly
			(pts
				(xy -2.984754 -2.229612) (xy -2.765806 -1.57226) (xy -3.423158 -1.791462)
			)
			(stroke
				(width 0)
				(type default)
			)
			(fill yes)
			(layer "F.SilkS")
		)
		(fp_line
			(start 1.549908 -1.549908)
			(end 1.549908 1.549908)
			(stroke
				(width 0.1)
				(type default)
			)
			(layer "F.Fab")
		)
		(fp_line
			(start -1.549908 -1.549908)
			(end 1.549908 -1.549908)
			(stroke
				(width 0.1)
				(type default)
			)
			(layer "F.Fab")
		)
		(fp_line
			(start 1.549908 1.549908)
			(end -1.549908 1.549908)
			(stroke
				(width 0.1)
				(type default)
			)
			(layer "F.Fab")
		)
		(fp_line
			(start -1.549908 1.549908)
			(end -1.549908 -1.549908)
			(stroke
				(width 0.1)
				(type default)
			)
			(layer "F.Fab")
		)
		(fp_poly
			(pts
				(xy -3.4798 -1.359916) (xy -2.86004 -1.050036) (xy -3.4798 -0.740156)
			)
			(stroke
				(width 0)
				(type default)
			)
			(fill yes)
			(layer "F.Fab")
		)
		(pad "1" smd rect
			(at -2.175002 -1.050036 180)
			(size 0.6096 1.1684)
			(layers "F.Cu" "F.Mask" "F.Paste")
			(net "P3V3_AUX")
		)
		(pad "2" smd rect
			(at -2.175002 -0.32512 180)
			(size 0.4318 1.1684)
			(layers "F.Cu" "F.Mask" "F.Paste")
			(net "SMB_MB_I3C_ISO_SCL")
		)
		(pad "3" smd rect
			(at -2.175002 0.32512 180)
			(size 0.4318 1.1684)
			(layers "F.Cu" "F.Mask" "F.Paste")
			(net "SMB_MB_I3C_ISO_SDA")
		)
		(pad "4" smd rect
			(at -2.175002 1.050036 180)
			(size 0.6096 1.1684)
			(layers "F.Cu" "F.Mask" "F.Paste")
			(net "GND")
		)
		(pad "5" smd rect
			(at 2.175002 1.050036 180)
			(size 0.6096 1.1684)
			(layers "F.Cu" "F.Mask" "F.Paste")
			(net "MB_I3C_ISO_EN")
		)
		(pad "6" smd rect
			(at 2.175002 0.32512 180)
			(size 0.4318 1.1684)
			(layers "F.Cu" "F.Mask" "F.Paste")
			(net "I3C_MB_BMC_R_SDA")
		)
		(pad "7" smd rect
			(at 2.175002 -0.32512 180)
			(size 0.4318 1.1684)
			(layers "F.Cu" "F.Mask" "F.Paste")
			(net "I3C_MB_BMC_R_SCL")
		)
		(pad "8" smd rect
			(at 2.175002 -1.050036 180)
			(size 0.6096 1.1684)
			(layers "F.Cu" "F.Mask" "F.Paste")
			(net "P3V3_AUX")
		)
	)
	(footprint ""
		(layer "F.Cu")
		(at 210.439 -192.659 180)
		(property "Reference" "R1533"
			(at 0 0 180)
			(layer "F.SilkS")
			(hide yes)
			(effects
				(font
					(size 1.27 1.27)
				)
			)
		)
		(property "Value" ""
			(at 0 0 180)
			(layer "F.Fab")
			(effects
				(font
					(size 1.27 1.27)
				)
			)
		)
		(duplicate_pad_numbers_are_jumpers no)
		(fp_line
			(start 0.7874 0.4064)
			(end -0.7874 0.4064)
			(stroke
				(width 0.1524)
				(type default)
			)
			(layer "F.SilkS")
		)
		(fp_line
			(start 0.7874 -0.4064)
			(end 0.7874 0.4064)
			(stroke
				(width 0.1524)
				(type default)
			)
			(layer "F.SilkS")
		)
		(fp_line
			(start -0.7874 0.4064)
			(end -0.7874 -0.4064)
			(stroke
				(width 0.1524)
				(type default)
			)
			(layer "F.SilkS")
		)
		(fp_line
			(start -0.7874 -0.4064)
			(end 0.7874 -0.4064)
			(stroke
				(width 0.1524)
				(type default)
			)
			(layer "F.SilkS")
		)
		(fp_line
			(start 0.67945 0.3048)
			(end 0.120396 0.3048)
			(stroke
				(width 0.1)
				(type default)
			)
			(layer "F.Fab")
		)
		(fp_line
			(start 0.67945 -0.3048)
			(end 0.67945 0.3048)
			(stroke
				(width 0.1)
				(type default)
			)
			(layer "F.Fab")
		)
		(fp_line
			(start 0.12065 -0.2794)
			(end 0.12065 -0.3048)
			(stroke
				(width 0.1)
				(type default)
			)
			(layer "F.Fab")
		)
		(fp_line
			(start 0.12065 -0.3048)
			(end 0.67945 -0.3048)
			(stroke
				(width 0.1)
				(type default)
			)
			(layer "F.Fab")
		)
		(fp_line
			(start 0.120396 0.3048)
			(end 0.120396 0.2794)
			(stroke
				(width 0.1)
				(type default)
			)
			(layer "F.Fab")
		)
		(fp_line
			(start 0.120396 0.2794)
			(end -0.12065 0.2794)
			(stroke
				(width 0.1)
				(type default)
			)
			(layer "F.Fab")
		)
		(fp_line
			(start -0.12065 0.3048)
			(end -0.67945 0.3048)
			(stroke
				(width 0.1)
				(type default)
			)
			(layer "F.Fab")
		)
		(fp_line
			(start -0.12065 0.2794)
			(end -0.12065 0.3048)
			(stroke
				(width 0.1)
				(type default)
			)
			(layer "F.Fab")
		)
		(fp_line
			(start -0.12065 -0.2794)
			(end 0.12065 -0.2794)
			(stroke
				(width 0.1)
				(type default)
			)
			(layer "F.Fab")
		)
		(fp_line
			(start -0.12065 -0.305054)
			(end -0.12065 -0.2794)
			(stroke
				(width 0.1)
				(type default)
			)
			(layer "F.Fab")
		)
		(fp_line
			(start -0.67945 0.3048)
			(end -0.67945 -0.305054)
			(stroke
				(width 0.1)
				(type default)
			)
			(layer "F.Fab")
		)
		(fp_line
			(start -0.67945 -0.305054)
			(end -0.12065 -0.305054)
			(stroke
				(width 0.1)
				(type default)
			)
			(layer "F.Fab")
		)
		(pad "1" smd circle
			(at -0.40005 0 180)
			(size 0 0)
			(layers "F.Cu" "F.Mask" "F.Paste")
			(net "SMB_NIC7_R_SCL")
		)
		(pad "2" smd circle
			(at 0.40005 0 180)
			(size 0 0)
			(layers "F.Cu" "F.Mask" "F.Paste")
			(net "P1V2_AUX")
		)
	)
	(footprint ""
		(layer "F.Cu")
		(at 45.246798 -38.49116 180)
		(property "Reference" "R5888"
			(at 0 0 180)
			(layer "F.SilkS")
			(hide yes)
			(effects
				(font
					(size 1.27 1.27)
				)
			)
		)
		(property "Value" ""
			(at 0 0 180)
			(layer "F.Fab")
			(effects
				(font
					(size 1.27 1.27)
				)
			)
		)
		(duplicate_pad_numbers_are_jumpers no)
		(fp_line
			(start 0.7874 0.4064)
			(end -0.7874 0.4064)
			(stroke
				(width 0.1524)
				(type default)
			)
			(layer "F.SilkS")
		)
		(fp_line
			(start 0.7874 -0.4064)
			(end 0.7874 0.4064)
			(stroke
				(width 0.1524)
				(type default)
			)
			(layer "F.SilkS")
		)
		(fp_line
			(start -0.7874 0.4064)
			(end -0.7874 -0.4064)
			(stroke
				(width 0.1524)
				(type default)
			)
			(layer "F.SilkS")
		)
		(fp_line
			(start -0.7874 -0.4064)
			(end 0.7874 -0.4064)
			(stroke
				(width 0.1524)
				(type default)
			)
			(layer "F.SilkS")
		)
		(fp_line
			(start 0.67945 0.3048)
			(end 0.120396 0.3048)
			(stroke
				(width 0.1)
				(type default)
			)
			(layer "F.Fab")
		)
		(fp_line
			(start 0.67945 -0.3048)
			(end 0.67945 0.3048)
			(stroke
				(width 0.1)
				(type default)
			)
			(layer "F.Fab")
		)
		(fp_line
			(start 0.12065 -0.2794)
			(end 0.12065 -0.3048)
			(stroke
				(width 0.1)
				(type default)
			)
			(layer "F.Fab")
		)
		(fp_line
			(start 0.12065 -0.3048)
			(end 0.67945 -0.3048)
			(stroke
				(width 0.1)
				(type default)
			)
			(layer "F.Fab")
		)
		(fp_line
			(start 0.120396 0.3048)
			(end 0.120396 0.2794)
			(stroke
				(width 0.1)
				(type default)
			)
			(layer "F.Fab")
		)
		(fp_line
			(start 0.120396 0.2794)
			(end -0.12065 0.2794)
			(stroke
				(width 0.1)
				(type default)
			)
			(layer "F.Fab")
		)
		(fp_line
			(start -0.12065 0.3048)
			(end -0.67945 0.3048)
			(stroke
				(width 0.1)
				(type default)
			)
			(layer "F.Fab")
		)
		(fp_line
			(start -0.12065 0.2794)
			(end -0.12065 0.3048)
			(stroke
				(width 0.1)
				(type default)
			)
			(layer "F.Fab")
		)
		(fp_line
			(start -0.12065 -0.2794)
			(end 0.12065 -0.2794)
			(stroke
				(width 0.1)
				(type default)
			)
			(layer "F.Fab")
		)
		(fp_line
			(start -0.12065 -0.305054)
			(end -0.12065 -0.2794)
			(stroke
				(width 0.1)
				(type default)
			)
			(layer "F.Fab")
		)
		(fp_line
			(start -0.67945 0.3048)
			(end -0.67945 -0.305054)
			(stroke
				(width 0.1)
				(type default)
			)
			(layer "F.Fab")
		)
		(fp_line
			(start -0.67945 -0.305054)
			(end -0.12065 -0.305054)
			(stroke
				(width 0.1)
				(type default)
			)
			(layer "F.Fab")
		)
		(pad "1" smd circle
			(at -0.40005 0 180)
			(size 0 0)
			(layers "F.Cu" "F.Mask" "F.Paste")
			(net "P3V3_SSD2_PG_G1")
		)
		(pad "2" smd circle
			(at 0.40005 0 180)
			(size 0 0)
			(layers "F.Cu" "F.Mask" "F.Paste")
			(net "GND")
		)
	)
	(footprint ""
		(layer "F.Cu")
		(at 20.239736 -152.71115 90)
		(property "Reference" "R683"
			(at 0 0 90)
			(layer "F.SilkS")
			(hide yes)
			(effects
				(font
					(size 1.27 1.27)
				)
			)
		)
		(property "Value" ""
			(at 0 0 90)
			(layer "F.Fab")
			(effects
				(font
					(size 1.27 1.27)
				)
			)
		)
		(duplicate_pad_numbers_are_jumpers no)
		(fp_line
			(start 0.7874 -0.4064)
			(end 0.7874 0.4064)
			(stroke
				(width 0.1524)
				(type default)
			)
			(layer "F.SilkS")
		)
		(fp_line
			(start -0.7874 -0.4064)
			(end 0.7874 -0.4064)
			(stroke
				(width 0.1524)
				(type default)
			)
			(layer "F.SilkS")
		)
		(fp_line
			(start 0.7874 0.4064)
			(end -0.7874 0.4064)
			(stroke
				(width 0.1524)
				(type default)
			)
			(layer "F.SilkS")
		)
		(fp_line
			(start -0.7874 0.4064)
			(end -0.7874 -0.4064)
			(stroke
				(width 0.1524)
				(type default)
			)
			(layer "F.SilkS")
		)
		(fp_line
			(start -0.12065 -0.305054)
			(end -0.12065 -0.2794)
			(stroke
				(width 0.1)
				(type default)
			)
			(layer "F.Fab")
		)
		(fp_line
			(start -0.67945 -0.305054)
			(end -0.12065 -0.305054)
			(stroke
				(width 0.1)
				(type default)
			)
			(layer "F.Fab")
		)
		(fp_line
			(start 0.67945 -0.3048)
			(end 0.67945 0.3048)
			(stroke
				(width 0.1)
				(type default)
			)
			(layer "F.Fab")
		)
		(fp_line
			(start 0.12065 -0.3048)
			(end 0.67945 -0.3048)
			(stroke
				(width 0.1)
				(type default)
			)
			(layer "F.Fab")
		)
		(fp_line
			(start 0.12065 -0.2794)
			(end 0.12065 -0.3048)
			(stroke
				(width 0.1)
				(type default)
			)
			(layer "F.Fab")
		)
		(fp_line
			(start -0.12065 -0.2794)
			(end 0.12065 -0.2794)
			(stroke
				(width 0.1)
				(type default)
			)
			(layer "F.Fab")
		)
		(fp_line
			(start 0.120396 0.2794)
			(end -0.12065 0.2794)
			(stroke
				(width 0.1)
				(type default)
			)
			(layer "F.Fab")
		)
		(fp_line
			(start -0.12065 0.2794)
			(end -0.12065 0.3048)
			(stroke
				(width 0.1)
				(type default)
			)
			(layer "F.Fab")
		)
		(fp_line
			(start 0.67945 0.3048)
			(end 0.120396 0.3048)
			(stroke
				(width 0.1)
				(type default)
			)
			(layer "F.Fab")
		)
		(fp_line
			(start 0.120396 0.3048)
			(end 0.120396 0.2794)
			(stroke
				(width 0.1)
				(type default)
			)
			(layer "F.Fab")
		)
		(fp_line
			(start -0.12065 0.3048)
			(end -0.67945 0.3048)
			(stroke
				(width 0.1)
				(type default)
			)
			(layer "F.Fab")
		)
		(fp_line
			(start -0.67945 0.3048)
			(end -0.67945 -0.305054)
			(stroke
				(width 0.1)
				(type default)
			)
			(layer "F.Fab")
		)
		(pad "1" smd circle
			(at -0.40005 0 90)
			(size 0 0)
			(layers "F.Cu" "F.Mask" "F.Paste")
			(net "NIC0_ADC_A0")
		)
		(pad "2" smd circle
			(at 0.40005 0 90)
			(size 0 0)
			(layers "F.Cu" "F.Mask" "F.Paste")
			(net "P3V3_AUX")
		)
	)
	(footprint ""
		(layer "F.Cu")
		(at 248.094754 -279.567386 180)
		(property "Reference" "R798"
			(at 0 0 180)
			(layer "F.SilkS")
			(hide yes)
			(effects
				(font
					(size 1.27 1.27)
				)
			)
		)
		(property "Value" ""
			(at 0 0 180)
			(layer "F.Fab")
			(effects
				(font
					(size 1.27 1.27)
				)
			)
		)
		(duplicate_pad_numbers_are_jumpers no)
		(fp_line
			(start 0.7874 0.4064)
			(end -0.7874 0.4064)
			(stroke
				(width 0.1524)
				(type default)
			)
			(layer "F.SilkS")
		)
		(fp_line
			(start 0.7874 -0.4064)
			(end 0.7874 0.4064)
			(stroke
				(width 0.1524)
				(type default)
			)
			(layer "F.SilkS")
		)
		(fp_line
			(start -0.7874 0.4064)
			(end -0.7874 -0.4064)
			(stroke
				(width 0.1524)
				(type default)
			)
			(layer "F.SilkS")
		)
		(fp_line
			(start -0.7874 -0.4064)
			(end 0.7874 -0.4064)
			(stroke
				(width 0.1524)
				(type default)
			)
			(layer "F.SilkS")
		)
		(fp_line
			(start 0.67945 0.3048)
			(end 0.120396 0.3048)
			(stroke
				(width 0.1)
				(type default)
			)
			(layer "F.Fab")
		)
		(fp_line
			(start 0.67945 -0.3048)
			(end 0.67945 0.3048)
			(stroke
				(width 0.1)
				(type default)
			)
			(layer "F.Fab")
		)
		(fp_line
			(start 0.12065 -0.2794)
			(end 0.12065 -0.3048)
			(stroke
				(width 0.1)
				(type default)
			)
			(layer "F.Fab")
		)
		(fp_line
			(start 0.12065 -0.3048)
			(end 0.67945 -0.3048)
			(stroke
				(width 0.1)
				(type default)
			)
			(layer "F.Fab")
		)
		(fp_line
			(start 0.120396 0.3048)
			(end 0.120396 0.2794)
			(stroke
				(width 0.1)
				(type default)
			)
			(layer "F.Fab")
		)
		(fp_line
			(start 0.120396 0.2794)
			(end -0.12065 0.2794)
			(stroke
				(width 0.1)
				(type default)
			)
			(layer "F.Fab")
		)
		(fp_line
			(start -0.12065 0.3048)
			(end -0.67945 0.3048)
			(stroke
				(width 0.1)
				(type default)
			)
			(layer "F.Fab")
		)
		(fp_line
			(start -0.12065 0.2794)
			(end -0.12065 0.3048)
			(stroke
				(width 0.1)
				(type default)
			)
			(layer "F.Fab")
		)
		(fp_line
			(start -0.12065 -0.2794)
			(end 0.12065 -0.2794)
			(stroke
				(width 0.1)
				(type default)
			)
			(layer "F.Fab")
		)
		(fp_line
			(start -0.12065 -0.305054)
			(end -0.12065 -0.2794)
			(stroke
				(width 0.1)
				(type default)
			)
			(layer "F.Fab")
		)
		(fp_line
			(start -0.67945 0.3048)
			(end -0.67945 -0.305054)
			(stroke
				(width 0.1)
				(type default)
			)
			(layer "F.Fab")
		)
		(fp_line
			(start -0.67945 -0.305054)
			(end -0.12065 -0.305054)
			(stroke
				(width 0.1)
				(type default)
			)
			(layer "F.Fab")
		)
		(pad "1" smd circle
			(at -0.40005 0 180)
			(size 0 0)
			(layers "F.Cu" "F.Mask" "F.Paste")
			(net "SMB_BIC_I2C6_MUX_PEX_ADC_R_SDA")
		)
		(pad "2" smd circle
			(at 0.40005 0 180)
			(size 0 0)
			(layers "F.Cu" "F.Mask" "F.Paste")
			(net "SMB_PEX2_P1V25_ADC_SDA")
		)
	)
)
